(kicad_sch (version 20211123) (generator eeschema)

  (paper "A3")

  (title_block
    (title "SA800U (Snapdragon 845) Baseboard")
    (date "2023-10-19")
    (rev "1.0.3")
    (company "Antmicro Ltd.")
    (comment 1 "www.antmicro.com")
  )

  (junction (at 368.808 117.348) (diameter 0) (color 0 0 0 0)
  )
  (junction (at 117.856 117.348) (diameter 0) (color 0 0 0 0)
  )
  (junction (at 345.948 117.348) (diameter 0) (color 0 0 0 0)
  )
  (junction (at 217.678 117.348) (diameter 0) (color 0 0 0 0)
  )
  (junction (at 357.378 117.348) (diameter 0) (color 0 0 0 0)
  )
  (junction (at 139.573 146.558) (diameter 0) (color 0 0 0 0)
  )
  (junction (at 139.573 117.348) (diameter 0) (color 0 0 0 0)
  )
  (junction (at 337.312 132.588) (diameter 0) (color 0 0 0 0)
  )
  (junction (at 320.548 132.588) (diameter 0) (color 0 0 0 0)
  )
  (junction (at 147.193 140.208) (diameter 0) (color 0 0 0 0)
  )
  (junction (at 307.848 124.968) (diameter 0) (color 0 0 0 0)
  )
  (junction (at 64.008 130.048) (diameter 0) (color 0 0 0 0)
  )
  (junction (at 267.843 117.348) (diameter 0) (color 0 0 0 0)
  )
  (junction (at 88.138 117.348) (diameter 0) (color 0 0 0 0)
  )
  (junction (at 333.248 132.588) (diameter 0) (color 0 0 0 0)
  )
  (junction (at 217.678 127.508) (diameter 0) (color 0 0 0 0)
  )
  (junction (at 251.968 132.588) (diameter 0) (color 0 0 0 0)
  )
  (junction (at 368.808 132.588) (diameter 0) (color 0 0 0 0)
  )
  (junction (at 187.833 131.318) (diameter 0) (color 0 0 0 0)
  )
  (junction (at 111.252 146.558) (diameter 0) (color 0 0 0 0)
  )
  (junction (at 117.856 146.558) (diameter 0) (color 0 0 0 0)
  )
  (junction (at 267.843 132.588) (diameter 0) (color 0 0 0 0)
  )
  (junction (at 336.423 117.348) (diameter 0) (color 0 0 0 0)
  )
  (junction (at 146.558 117.348) (diameter 0) (color 0 0 0 0)
  )
  (junction (at 123.19 146.558) (diameter 0) (color 0 0 0 0)
  )
  (junction (at 333.248 117.348) (diameter 0) (color 0 0 0 0)
  )
  (junction (at 187.833 117.348) (diameter 0) (color 0 0 0 0)
  )
  (junction (at 251.968 117.348) (diameter 0) (color 0 0 0 0)
  )
  (junction (at 357.378 132.588) (diameter 0) (color 0 0 0 0)
  )
  (junction (at 271.018 105.918) (diameter 0) (color 0 0 0 0)
  )
  (junction (at 320.548 117.348) (diameter 0) (color 0 0 0 0)
  )
  (junction (at 345.948 132.588) (diameter 0) (color 0 0 0 0)
  )
  (junction (at 123.19 117.348) (diameter 0) (color 0 0 0 0)
  )

  (wire (pts (xy 217.678 124.333) (xy 217.678 127.508))
    (stroke (width 0) (type default) (color 0 0 0 0))
  )
  (wire (pts (xy 187.833 131.318) (xy 204.978 131.318))
    (stroke (width 0) (type default) (color 0 0 0 0))
  )
  (wire (pts (xy 320.548 132.588) (xy 320.548 123.698))
    (stroke (width 0) (type default) (color 0 0 0 0))
  )
  (wire (pts (xy 180.213 126.238) (xy 180.213 137.668))
    (stroke (width 0) (type default) (color 0 0 0 0))
  )
  (wire (pts (xy 139.573 135.128) (xy 139.573 138.43))
    (stroke (width 0) (type default) (color 0 0 0 0))
  )
  (wire (pts (xy 85.598 144.018) (xy 88.138 144.018))
    (stroke (width 0) (type default) (color 0 0 0 0))
  )
  (wire (pts (xy 251.968 133.858) (xy 251.968 132.588))
    (stroke (width 0) (type default) (color 0 0 0 0))
  )
  (wire (pts (xy 88.138 117.348) (xy 102.235 117.348))
    (stroke (width 0) (type default) (color 0 0 0 0))
  )
  (wire (pts (xy 168.783 131.318) (xy 180.848 131.318))
    (stroke (width 0) (type default) (color 0 0 0 0))
  )
  (wire (pts (xy 307.848 112.268) (xy 307.848 124.968))
    (stroke (width 0) (type default) (color 0 0 0 0))
  )
  (wire (pts (xy 217.678 134.493) (xy 217.678 136.398))
    (stroke (width 0) (type default) (color 0 0 0 0))
  )
  (wire (pts (xy 307.848 124.968) (xy 307.848 137.795))
    (stroke (width 0) (type default) (color 0 0 0 0))
  )
  (wire (pts (xy 251.968 117.348) (xy 267.843 117.348))
    (stroke (width 0) (type default) (color 0 0 0 0))
  )
  (wire (pts (xy 123.19 116.078) (xy 123.19 117.348))
    (stroke (width 0) (type default) (color 0 0 0 0))
  )
  (wire (pts (xy 333.248 123.698) (xy 333.248 132.588))
    (stroke (width 0) (type default) (color 0 0 0 0))
  )
  (wire (pts (xy 217.678 127.508) (xy 227.838 127.508))
    (stroke (width 0) (type default) (color 0 0 0 0))
  )
  (wire (pts (xy 201.168 144.145) (xy 201.168 145.288))
    (stroke (width 0) (type default) (color 0 0 0 0))
  )
  (wire (pts (xy 333.248 117.348) (xy 333.248 118.618))
    (stroke (width 0) (type default) (color 0 0 0 0))
  )
  (wire (pts (xy 107.315 117.348) (xy 117.856 117.348))
    (stroke (width 0) (type default) (color 0 0 0 0))
  )
  (wire (pts (xy 267.843 117.348) (xy 267.843 123.317))
    (stroke (width 0) (type default) (color 0 0 0 0))
  )
  (wire (pts (xy 62.738 112.268) (xy 67.818 112.268))
    (stroke (width 0) (type default) (color 0 0 0 0))
  )
  (wire (pts (xy 357.378 132.588) (xy 345.948 132.588))
    (stroke (width 0) (type default) (color 0 0 0 0))
  )
  (wire (pts (xy 139.573 128.778) (xy 148.463 128.778))
    (stroke (width 0) (type default) (color 0 0 0 0))
  )
  (wire (pts (xy 336.423 117.348) (xy 345.948 117.348))
    (stroke (width 0) (type default) (color 0 0 0 0))
  )
  (wire (pts (xy 271.018 104.267) (xy 271.018 105.918))
    (stroke (width 0) (type default) (color 0 0 0 0))
  )
  (wire (pts (xy 345.948 123.698) (xy 345.948 132.588))
    (stroke (width 0) (type default) (color 0 0 0 0))
  )
  (wire (pts (xy 117.856 136.398) (xy 117.856 146.558))
    (stroke (width 0) (type default) (color 0 0 0 0))
  )
  (wire (pts (xy 187.833 131.318) (xy 187.833 132.207))
    (stroke (width 0) (type default) (color 0 0 0 0))
  )
  (wire (pts (xy 251.968 117.348) (xy 251.968 123.317))
    (stroke (width 0) (type default) (color 0 0 0 0))
  )
  (wire (pts (xy 368.808 132.588) (xy 368.808 133.858))
    (stroke (width 0) (type default) (color 0 0 0 0))
  )
  (wire (pts (xy 368.808 117.348) (xy 377.063 117.348))
    (stroke (width 0) (type default) (color 0 0 0 0))
  )
  (wire (pts (xy 187.833 137.287) (xy 187.833 145.288))
    (stroke (width 0) (type default) (color 0 0 0 0))
  )
  (wire (pts (xy 307.848 137.795) (xy 311.531 137.795))
    (stroke (width 0) (type default) (color 0 0 0 0))
  )
  (wire (pts (xy 187.833 117.348) (xy 187.833 121.793))
    (stroke (width 0) (type default) (color 0 0 0 0))
  )
  (wire (pts (xy 64.008 130.048) (xy 64.008 144.018))
    (stroke (width 0) (type default) (color 0 0 0 0))
  )
  (wire (pts (xy 273.558 124.968) (xy 271.018 124.968))
    (stroke (width 0) (type default) (color 0 0 0 0))
  )
  (wire (pts (xy 267.843 132.588) (xy 267.843 128.397))
    (stroke (width 0) (type default) (color 0 0 0 0))
  )
  (wire (pts (xy 123.19 146.558) (xy 139.573 146.558))
    (stroke (width 0) (type default) (color 0 0 0 0))
  )
  (wire (pts (xy 147.193 137.668) (xy 147.193 140.208))
    (stroke (width 0) (type default) (color 0 0 0 0))
  )
  (wire (pts (xy 357.378 117.348) (xy 368.808 117.348))
    (stroke (width 0) (type default) (color 0 0 0 0))
  )
  (wire (pts (xy 257.683 105.918) (xy 271.018 105.918))
    (stroke (width 0) (type default) (color 0 0 0 0))
  )
  (wire (pts (xy 251.968 132.588) (xy 267.843 132.588))
    (stroke (width 0) (type default) (color 0 0 0 0))
  )
  (wire (pts (xy 337.312 132.588) (xy 345.948 132.588))
    (stroke (width 0) (type default) (color 0 0 0 0))
  )
  (wire (pts (xy 357.378 132.588) (xy 368.808 132.588))
    (stroke (width 0) (type default) (color 0 0 0 0))
  )
  (wire (pts (xy 336.423 115.824) (xy 336.423 117.348))
    (stroke (width 0) (type default) (color 0 0 0 0))
  )
  (wire (pts (xy 111.252 146.05) (xy 111.252 146.558))
    (stroke (width 0) (type default) (color 0 0 0 0))
  )
  (wire (pts (xy 168.783 126.238) (xy 180.213 126.238))
    (stroke (width 0) (type default) (color 0 0 0 0))
  )
  (wire (pts (xy 139.573 120.65) (xy 139.573 117.348))
    (stroke (width 0) (type default) (color 0 0 0 0))
  )
  (wire (pts (xy 195.453 144.145) (xy 195.453 145.288))
    (stroke (width 0) (type default) (color 0 0 0 0))
  )
  (wire (pts (xy 368.808 118.618) (xy 368.808 117.348))
    (stroke (width 0) (type default) (color 0 0 0 0))
  )
  (wire (pts (xy 117.856 146.558) (xy 123.19 146.558))
    (stroke (width 0) (type default) (color 0 0 0 0))
  )
  (wire (pts (xy 333.248 117.348) (xy 336.423 117.348))
    (stroke (width 0) (type default) (color 0 0 0 0))
  )
  (wire (pts (xy 123.19 117.348) (xy 139.573 117.348))
    (stroke (width 0) (type default) (color 0 0 0 0))
  )
  (wire (pts (xy 333.248 132.588) (xy 320.548 132.588))
    (stroke (width 0) (type default) (color 0 0 0 0))
  )
  (wire (pts (xy 345.948 117.348) (xy 345.948 118.618))
    (stroke (width 0) (type default) (color 0 0 0 0))
  )
  (wire (pts (xy 91.44 146.558) (xy 102.87 146.558))
    (stroke (width 0) (type default) (color 0 0 0 0))
  )
  (wire (pts (xy 117.856 117.348) (xy 123.19 117.348))
    (stroke (width 0) (type default) (color 0 0 0 0))
  )
  (wire (pts (xy 267.843 117.348) (xy 273.558 117.348))
    (stroke (width 0) (type default) (color 0 0 0 0))
  )
  (wire (pts (xy 107.95 146.558) (xy 111.252 146.558))
    (stroke (width 0) (type default) (color 0 0 0 0))
  )
  (wire (pts (xy 91.44 130.048) (xy 91.44 146.558))
    (stroke (width 0) (type default) (color 0 0 0 0))
  )
  (wire (pts (xy 148.463 137.668) (xy 147.193 137.668))
    (stroke (width 0) (type default) (color 0 0 0 0))
  )
  (wire (pts (xy 67.818 117.348) (xy 64.008 117.348))
    (stroke (width 0) (type default) (color 0 0 0 0))
  )
  (wire (pts (xy 251.968 128.397) (xy 251.968 132.588))
    (stroke (width 0) (type default) (color 0 0 0 0))
  )
  (wire (pts (xy 64.008 144.018) (xy 67.818 144.018))
    (stroke (width 0) (type default) (color 0 0 0 0))
  )
  (wire (pts (xy 123.19 134.366) (xy 123.19 146.558))
    (stroke (width 0) (type default) (color 0 0 0 0))
  )
  (wire (pts (xy 146.558 126.238) (xy 146.558 117.348))
    (stroke (width 0) (type default) (color 0 0 0 0))
  )
  (wire (pts (xy 64.008 130.048) (xy 91.44 130.048))
    (stroke (width 0) (type default) (color 0 0 0 0))
  )
  (wire (pts (xy 123.19 117.348) (xy 123.19 129.286))
    (stroke (width 0) (type default) (color 0 0 0 0))
  )
  (wire (pts (xy 168.783 140.208) (xy 172.593 140.208))
    (stroke (width 0) (type default) (color 0 0 0 0))
  )
  (wire (pts (xy 273.558 132.588) (xy 267.843 132.588))
    (stroke (width 0) (type default) (color 0 0 0 0))
  )
  (wire (pts (xy 217.678 117.348) (xy 251.968 117.348))
    (stroke (width 0) (type default) (color 0 0 0 0))
  )
  (wire (pts (xy 148.463 135.128) (xy 139.573 135.128))
    (stroke (width 0) (type default) (color 0 0 0 0))
  )
  (wire (pts (xy 146.558 117.348) (xy 187.833 117.348))
    (stroke (width 0) (type default) (color 0 0 0 0))
  )
  (wire (pts (xy 139.573 128.778) (xy 139.573 125.73))
    (stroke (width 0) (type default) (color 0 0 0 0))
  )
  (wire (pts (xy 148.463 126.238) (xy 146.558 126.238))
    (stroke (width 0) (type default) (color 0 0 0 0))
  )
  (wire (pts (xy 217.678 117.348) (xy 217.678 119.253))
    (stroke (width 0) (type default) (color 0 0 0 0))
  )
  (wire (pts (xy 62.738 138.938) (xy 67.818 138.938))
    (stroke (width 0) (type default) (color 0 0 0 0))
  )
  (wire (pts (xy 307.848 112.268) (xy 311.531 112.268))
    (stroke (width 0) (type default) (color 0 0 0 0))
  )
  (wire (pts (xy 139.573 146.558) (xy 147.193 146.558))
    (stroke (width 0) (type default) (color 0 0 0 0))
  )
  (wire (pts (xy 85.598 117.348) (xy 88.138 117.348))
    (stroke (width 0) (type default) (color 0 0 0 0))
  )
  (wire (pts (xy 123.19 146.558) (xy 123.19 148.082))
    (stroke (width 0) (type default) (color 0 0 0 0))
  )
  (wire (pts (xy 320.548 137.795) (xy 320.548 132.588))
    (stroke (width 0) (type default) (color 0 0 0 0))
  )
  (wire (pts (xy 357.378 123.698) (xy 357.378 132.588))
    (stroke (width 0) (type default) (color 0 0 0 0))
  )
  (wire (pts (xy 293.878 117.348) (xy 320.548 117.348))
    (stroke (width 0) (type default) (color 0 0 0 0))
  )
  (wire (pts (xy 117.856 114.808) (xy 117.856 117.348))
    (stroke (width 0) (type default) (color 0 0 0 0))
  )
  (wire (pts (xy 67.818 149.098) (xy 62.738 149.098))
    (stroke (width 0) (type default) (color 0 0 0 0))
  )
  (wire (pts (xy 147.193 140.208) (xy 148.463 140.208))
    (stroke (width 0) (type default) (color 0 0 0 0))
  )
  (wire (pts (xy 139.573 117.348) (xy 146.558 117.348))
    (stroke (width 0) (type default) (color 0 0 0 0))
  )
  (wire (pts (xy 320.548 117.348) (xy 333.248 117.348))
    (stroke (width 0) (type default) (color 0 0 0 0))
  )
  (wire (pts (xy 227.838 127.508) (xy 227.838 128.778))
    (stroke (width 0) (type default) (color 0 0 0 0))
  )
  (wire (pts (xy 185.928 131.318) (xy 187.833 131.318))
    (stroke (width 0) (type default) (color 0 0 0 0))
  )
  (wire (pts (xy 320.548 117.348) (xy 320.548 118.618))
    (stroke (width 0) (type default) (color 0 0 0 0))
  )
  (wire (pts (xy 67.818 122.428) (xy 62.738 122.428))
    (stroke (width 0) (type default) (color 0 0 0 0))
  )
  (wire (pts (xy 333.248 132.588) (xy 337.312 132.588))
    (stroke (width 0) (type default) (color 0 0 0 0))
  )
  (wire (pts (xy 187.833 117.348) (xy 217.678 117.348))
    (stroke (width 0) (type default) (color 0 0 0 0))
  )
  (wire (pts (xy 337.312 132.588) (xy 337.312 133.985))
    (stroke (width 0) (type default) (color 0 0 0 0))
  )
  (wire (pts (xy 111.252 146.558) (xy 117.856 146.558))
    (stroke (width 0) (type default) (color 0 0 0 0))
  )
  (wire (pts (xy 357.378 118.618) (xy 357.378 117.348))
    (stroke (width 0) (type default) (color 0 0 0 0))
  )
  (wire (pts (xy 293.878 132.588) (xy 320.548 132.588))
    (stroke (width 0) (type default) (color 0 0 0 0))
  )
  (wire (pts (xy 139.573 143.51) (xy 139.573 146.558))
    (stroke (width 0) (type default) (color 0 0 0 0))
  )
  (wire (pts (xy 180.213 142.748) (xy 180.213 145.288))
    (stroke (width 0) (type default) (color 0 0 0 0))
  )
  (wire (pts (xy 217.678 127.508) (xy 217.678 129.413))
    (stroke (width 0) (type default) (color 0 0 0 0))
  )
  (wire (pts (xy 345.948 117.348) (xy 357.378 117.348))
    (stroke (width 0) (type default) (color 0 0 0 0))
  )
  (wire (pts (xy 88.138 144.018) (xy 88.138 117.348))
    (stroke (width 0) (type default) (color 0 0 0 0))
  )
  (wire (pts (xy 117.856 127.508) (xy 117.856 117.348))
    (stroke (width 0) (type default) (color 0 0 0 0))
  )
  (wire (pts (xy 172.593 145.288) (xy 172.593 140.208))
    (stroke (width 0) (type default) (color 0 0 0 0))
  )
  (wire (pts (xy 320.548 117.348) (xy 320.548 112.268))
    (stroke (width 0) (type default) (color 0 0 0 0))
  )
  (wire (pts (xy 271.018 124.968) (xy 271.018 105.918))
    (stroke (width 0) (type default) (color 0 0 0 0))
  )
  (wire (pts (xy 368.808 123.698) (xy 368.808 132.588))
    (stroke (width 0) (type default) (color 0 0 0 0))
  )
  (wire (pts (xy 147.193 140.208) (xy 147.193 146.558))
    (stroke (width 0) (type default) (color 0 0 0 0))
  )
  (wire (pts (xy 316.611 137.795) (xy 320.548 137.795))
    (stroke (width 0) (type default) (color 0 0 0 0))
  )
  (wire (pts (xy 64.008 117.348) (xy 64.008 130.048))
    (stroke (width 0) (type default) (color 0 0 0 0))
  )
  (wire (pts (xy 168.783 128.778) (xy 170.434 128.778))
    (stroke (width 0) (type default) (color 0 0 0 0))
  )
  (wire (pts (xy 293.878 124.968) (xy 307.848 124.968))
    (stroke (width 0) (type default) (color 0 0 0 0))
  )
  (wire (pts (xy 316.611 112.268) (xy 320.548 112.268))
    (stroke (width 0) (type default) (color 0 0 0 0))
  )
  (wire (pts (xy 187.833 126.873) (xy 187.833 131.318))
    (stroke (width 0) (type default) (color 0 0 0 0))
  )

  (text "~10mA need to be drawn from PSE to maintain PoE.\nPDQE30-D draws 8~15mA with no load\nThis circuit provides exrta ~3mA and indicates VDD presence"
    (at 215.138 147.828 0)
    (effects (font (size 1.27 1.27)) (justify left bottom))
  )
  (text "FULL BRIDGE \nRECTIFIER!!" (at 68.453 94.488 0)
    (effects (font (size 2.0066 2.0066) (thickness 0.4013) bold) (justify left bottom))
  )
  (text "POE Controller" (at 151.003 91.313 0)
    (effects (font (size 2.0066 2.0066) (thickness 0.4013) bold) (justify left bottom))
  )
  (text "5V regulator" (at 279.273 91.313 0)
    (effects (font (size 2.0066 2.0066) (thickness 0.4013) bold) (justify left bottom))
  )
  (text "PoE" (at 12.7 17.78 0)
    (effects (font (size 2.9972 2.9972) (thickness 0.5994) bold) (justify left bottom))
  )
  (text "5V @6A" (at 378.333 115.443 0)
    (effects (font (size 1.27 1.27)) (justify left bottom))
  )

  (label "VSS_POE" (at 124.333 146.558 0)
    (effects (font (size 1.27 1.27)) (justify left bottom))
  )
  (label "SMPS_CTRL" (at 257.683 105.918 0)
    (effects (font (size 1.27 1.27)) (justify left bottom))
  )
  (label "SMPS_CTRL" (at 204.978 131.318 180)
    (effects (font (size 1.27 1.27)) (justify right bottom))
  )
  (label "VDD_POE" (at 194.183 117.348 0)
    (effects (font (size 1.27 1.27)) (justify left bottom))
  )
  (label "CLS" (at 148.463 135.128 180)
    (effects (font (size 1.27 1.27)) (justify right bottom))
  )
  (label "TRIM" (at 307.848 124.968 180)
    (effects (font (size 1.27 1.27)) (justify right bottom))
  )
  (label "DEN" (at 148.463 128.778 180)
    (effects (font (size 1.27 1.27)) (justify right bottom))
  )
  (label "CDB" (at 169.418 131.318 0)
    (effects (font (size 1.27 1.27)) (justify left bottom))
  )
  (label "APD" (at 172.593 126.238 0)
    (effects (font (size 1.27 1.27)) (justify left bottom))
  )

  (global_label "5V_POE" (shape output) (at 377.063 117.348 0) (fields_autoplaced)
    (effects (font (size 1.27 1.27)) (justify left))
    (property "Intersheet References" "${INTERSHEET_REFS}" (id 0) (at 386.4024 117.2686 0)
      (effects (font (size 1.27 1.27)) (justify left) hide)
    )
  )
  (global_label "PAIR45" (shape input) (at 62.738 149.098 180) (fields_autoplaced)
    (effects (font (size 1.27 1.27)) (justify right))
    (property "Intersheet References" "${INTERSHEET_REFS}" (id 0) (at -0.127 -0.127 0)
      (effects (font (size 1.27 1.27)) hide)
    )
  )
  (global_label "PAIR36" (shape input) (at 62.738 112.268 180) (fields_autoplaced)
    (effects (font (size 1.27 1.27)) (justify right))
    (property "Intersheet References" "${INTERSHEET_REFS}" (id 0) (at -0.127 -0.127 0)
      (effects (font (size 1.27 1.27)) hide)
    )
  )
  (global_label "PAIR12" (shape input) (at 62.738 122.428 180) (fields_autoplaced)
    (effects (font (size 1.27 1.27)) (justify right))
    (property "Intersheet References" "${INTERSHEET_REFS}" (id 0) (at -0.127 -0.127 0)
      (effects (font (size 1.27 1.27)) hide)
    )
  )
  (global_label "PAIR78" (shape input) (at 62.738 138.938 180) (fields_autoplaced)
    (effects (font (size 1.27 1.27)) (justify right))
    (property "Intersheet References" "${INTERSHEET_REFS}" (id 0) (at -0.127 -0.127 0)
      (effects (font (size 1.27 1.27)) hide)
    )
  )

  (symbol (lib_id "sa800u-baseboard-hw:R_0R_0402") (at 311.531 137.795 0) (unit 1)
    (in_bom yes) (on_board yes)
    (property "Reference" "R152" (id 0) (at 314.071 140.081 0)
      (effects (font (size 1.524 1.524)))
    )
    (property "Value" "R_0R_0402" (id 1) (at 311.531 141.605 0)
      (effects (font (size 1.524 1.524)) hide)
    )
    (property "Footprint" "sa800u-baseboard-hw-footprints:R_0402_1005Metric" (id 2) (at 316.611 132.715 0)
      (effects (font (size 1.524 1.524)) (justify left) hide)
    )
    (property "Datasheet" "https://industrial.panasonic.com/cdbs/www-data/pdf/RDA0000/AOA0000C301.pdf" (id 3) (at 311.531 137.795 0)
      (effects (font (size 1.27 1.27)) hide)
    )
    (property "Manufacturer" "Panasonic" (id 4) (at 316.611 127.635 0)
      (effects (font (size 1.524 1.524)) (justify left) hide)
    )
    (property "MPN" "ERJ2GE0R00X" (id 5) (at 316.611 130.175 0)
      (effects (font (size 1.524 1.524)) (justify left) hide)
    )
    (property "Val" "0R" (id 6) (at 314.325 142.113 0))
    (property "DNP" "DNP" (id 7) (at 314.071 137.922 0))
    (property "License" "Apache-2.0" (id 8) (at 331.851 163.195 0)
      (effects (font (size 1.27 1.27) (thickness 0.15)) (justify left bottom) hide)
    )
    (property "Author" "Antmicro" (id 9) (at 331.851 165.735 0)
      (effects (font (size 1.27 1.27) (thickness 0.15)) (justify left bottom) hide)
    )
    (property "Tolerance" "~" (id 10) (at 331.851 147.955 0)
      (effects (font (size 1.27 1.27)) (justify left bottom) hide)
    )
    (property "Current" "1A" (id 11) (at 331.851 168.275 0)
      (effects (font (size 1.27 1.27) (thickness 0.15)) (justify left bottom) hide)
    )
    (pin "1")
    (pin "2")
  )

  (symbol (lib_id "sa800u-baseboard-hw:GND") (at 368.808 133.858 0) (unit 1)
    (in_bom yes) (on_board yes) (fields_autoplaced)
    (property "Reference" "#PWR0250" (id 0) (at 368.808 140.208 0)
      (effects (font (size 1.27 1.27)) hide)
    )
    (property "Value" "GND" (id 1) (at 368.808 138.43 0))
    (property "Footprint" "" (id 2) (at 368.808 133.858 0)
      (effects (font (size 1.27 1.27)) hide)
    )
    (property "Datasheet" "" (id 3) (at 368.808 133.858 0)
      (effects (font (size 1.27 1.27)) hide)
    )
    (property "Author" "Antmicro" (id 4) (at 377.698 141.478 0)
      (effects (font (size 1.27 1.27) (thickness 0.15)) (justify left bottom) hide)
    )
    (property "License" "Apache-2.0" (id 5) (at 377.698 144.018 0)
      (effects (font (size 1.27 1.27) (thickness 0.15)) (justify left bottom) hide)
    )
    (pin "1")
  )

  (symbol (lib_id "sa800u-baseboard-hw:C_100n_0402") (at 368.808 118.618 270) (unit 1)
    (in_bom yes) (on_board yes) (fields_autoplaced)
    (property "Reference" "C151" (id 0) (at 371.856 119.8943 90)
      (effects (font (size 1.524 1.524)) (justify left))
    )
    (property "Value" "C_100n_0402" (id 1) (at 364.998 118.618 0)
      (effects (font (size 1.524 1.524)) hide)
    )
    (property "Footprint" "sa800u-baseboard-hw-footprints:C_0402_1005Metric" (id 2) (at 373.888 123.698 0)
      (effects (font (size 1.524 1.524)) (justify left) hide)
    )
    (property "Datasheet" "https://search.murata.co.jp/Ceramy/image/img/A01X/G101/ENG/GRM155R61H104KE14-01.pdf" (id 3) (at 368.808 118.618 0)
      (effects (font (size 1.27 1.27)) hide)
    )
    (property "Manufacturer" "Murata" (id 4) (at 378.968 123.698 0)
      (effects (font (size 1.524 1.524)) (justify left) hide)
    )
    (property "MPN" "GRM155R61H104KE14D" (id 5) (at 376.428 123.698 0)
      (effects (font (size 1.524 1.524)) (justify left) hide)
    )
    (property "Val" "100n" (id 6) (at 371.856 123.0692 90)
      (effects (font (size 1.27 1.27)) (justify left))
    )
    (property "License" "Apache-2.0" (id 7) (at 345.948 138.938 0)
      (effects (font (size 1.27 1.27) (thickness 0.15)) (justify left bottom) hide)
    )
    (property "Author" "Antmicro" (id 8) (at 343.408 138.938 0)
      (effects (font (size 1.27 1.27) (thickness 0.15)) (justify left bottom) hide)
    )
    (property "Voltage" "50V" (id 9) (at 340.868 138.938 0)
      (effects (font (size 1.27 1.27)) (justify left bottom) hide)
    )
    (property "Dielectric" "X5R" (id 10) (at 338.328 138.938 0)
      (effects (font (size 1.27 1.27)) (justify left bottom) hide)
    )
    (pin "1")
    (pin "2")
  )

  (symbol (lib_id "sa800u-baseboard-hw:C_1u_0402") (at 357.378 118.618 270) (unit 1)
    (in_bom yes) (on_board yes) (fields_autoplaced)
    (property "Reference" "C150" (id 0) (at 360.68 119.8943 90)
      (effects (font (size 1.524 1.524)) (justify left))
    )
    (property "Value" "C_1u_0402" (id 1) (at 353.568 118.618 0)
      (effects (font (size 1.524 1.524)) hide)
    )
    (property "Footprint" "sa800u-baseboard-hw-footprints:C_0402_1005Metric" (id 2) (at 362.458 123.698 0)
      (effects (font (size 1.524 1.524)) (justify left) hide)
    )
    (property "Datasheet" " " (id 3) (at 357.378 118.618 0)
      (effects (font (size 1.27 1.27)) hide)
    )
    (property "Manufacturer" "TDK" (id 4) (at 367.538 123.698 0)
      (effects (font (size 1.524 1.524)) (justify left) hide)
    )
    (property "MPN" "C1005X6S1A105K050BC" (id 5) (at 364.998 123.698 0)
      (effects (font (size 1.524 1.524)) (justify left) hide)
    )
    (property "Val" "1u" (id 6) (at 360.68 123.0692 90)
      (effects (font (size 1.27 1.27)) (justify left))
    )
    (property "License" "Apache-2.0" (id 7) (at 334.518 138.938 0)
      (effects (font (size 1.27 1.27) (thickness 0.15)) (justify left bottom) hide)
    )
    (property "Author" "Antmicro" (id 8) (at 331.978 138.938 0)
      (effects (font (size 1.27 1.27) (thickness 0.15)) (justify left bottom) hide)
    )
    (property "Voltage" "" (id 9) (at 329.438 138.938 0)
      (effects (font (size 1.27 1.27)) (justify left bottom) hide)
    )
    (property "Dielectric" "" (id 10) (at 326.898 138.938 0)
      (effects (font (size 1.27 1.27)) (justify left bottom) hide)
    )
    (pin "1")
    (pin "2")
  )

  (symbol (lib_id "sa800u-baseboard-hw:C_47u_0805") (at 345.948 118.618 270) (unit 1)
    (in_bom yes) (on_board yes) (fields_autoplaced)
    (property "Reference" "C149" (id 0) (at 349.377 119.8943 90)
      (effects (font (size 1.524 1.524)) (justify left))
    )
    (property "Value" "C_47u_0805" (id 1) (at 342.138 118.618 0)
      (effects (font (size 1.524 1.524)) hide)
    )
    (property "Footprint" "sa800u-baseboard-hw-footprints:C_0805_2012Metric" (id 2) (at 351.028 123.698 0)
      (effects (font (size 1.524 1.524)) (justify left) hide)
    )
    (property "Datasheet" " " (id 3) (at 345.948 118.618 0)
      (effects (font (size 1.27 1.27)) hide)
    )
    (property "Manufacturer" "KEMET" (id 4) (at 356.108 123.698 0)
      (effects (font (size 1.524 1.524)) (justify left) hide)
    )
    (property "MPN" "C0805C476M9PACTU" (id 5) (at 353.568 123.698 0)
      (effects (font (size 1.524 1.524)) (justify left) hide)
    )
    (property "Val" "47u" (id 6) (at 349.377 123.0692 90)
      (effects (font (size 1.27 1.27)) (justify left))
    )
    (property "License" "Apache-2.0" (id 7) (at 323.088 138.938 0)
      (effects (font (size 1.27 1.27) (thickness 0.15)) (justify left bottom) hide)
    )
    (property "Author" "Antmicro" (id 8) (at 320.548 138.938 0)
      (effects (font (size 1.27 1.27) (thickness 0.15)) (justify left bottom) hide)
    )
    (property "Voltage" "" (id 9) (at 318.008 138.938 0)
      (effects (font (size 1.27 1.27)) (justify left bottom) hide)
    )
    (property "Dielectric" "" (id 10) (at 315.468 138.938 0)
      (effects (font (size 1.27 1.27)) (justify left bottom) hide)
    )
    (pin "1")
    (pin "2")
  )

  (symbol (lib_id "sa800u-baseboard-hw:R_0R_0402") (at 311.531 112.268 0) (unit 1)
    (in_bom yes) (on_board yes)
    (property "Reference" "R151" (id 0) (at 313.944 108.204 0)
      (effects (font (size 1.524 1.524)))
    )
    (property "Value" "R_0R_0402" (id 1) (at 311.531 116.078 0)
      (effects (font (size 1.524 1.524)) hide)
    )
    (property "Footprint" "sa800u-baseboard-hw-footprints:R_0402_1005Metric" (id 2) (at 316.611 107.188 0)
      (effects (font (size 1.524 1.524)) (justify left) hide)
    )
    (property "Datasheet" "https://industrial.panasonic.com/cdbs/www-data/pdf/RDA0000/AOA0000C301.pdf" (id 3) (at 311.531 112.268 0)
      (effects (font (size 1.27 1.27)) hide)
    )
    (property "Manufacturer" "Panasonic" (id 4) (at 316.611 102.108 0)
      (effects (font (size 1.524 1.524)) (justify left) hide)
    )
    (property "MPN" "ERJ2GE0R00X" (id 5) (at 316.611 104.648 0)
      (effects (font (size 1.524 1.524)) (justify left) hide)
    )
    (property "Val" "0R" (id 6) (at 314.071 110.236 0))
    (property "DNP" "DNP" (id 7) (at 314.071 112.268 0))
    (property "License" "Apache-2.0" (id 8) (at 331.851 137.668 0)
      (effects (font (size 1.27 1.27) (thickness 0.15)) (justify left bottom) hide)
    )
    (property "Author" "Antmicro" (id 9) (at 331.851 140.208 0)
      (effects (font (size 1.27 1.27) (thickness 0.15)) (justify left bottom) hide)
    )
    (property "Tolerance" "~" (id 10) (at 331.851 122.428 0)
      (effects (font (size 1.27 1.27)) (justify left bottom) hide)
    )
    (property "Current" "1A" (id 11) (at 331.851 142.748 0)
      (effects (font (size 1.27 1.27) (thickness 0.15)) (justify left bottom) hide)
    )
    (pin "1")
    (pin "2")
  )

  (symbol (lib_id "sa800u-baseboard-hw:PDQE30-Q48-S5-D") (at 273.558 117.348 0) (unit 1)
    (in_bom yes) (on_board yes) (fields_autoplaced)
    (property "Reference" "PS1" (id 0) (at 283.718 137.16 0))
    (property "Value" "PDQE30-Q48-S5-D" (id 1) (at 283.718 139.7 0))
    (property "Footprint" "sa800u-baseboard-hw-footprints:CONV_PDQE30-Q48-S5-D" (id 2) (at 273.558 117.348 0)
      (effects (font (size 1.27 1.27)) (justify left bottom) hide)
    )
    (property "Datasheet" "https://www.cui.com/product/resource/pdqe30-d.pdf" (id 3) (at 273.558 117.348 0)
      (effects (font (size 1.27 1.27)) (justify left bottom) hide)
    )
    (property "STANDARD" "Manufacturer Recommendations" (id 4) (at 273.558 117.348 0)
      (effects (font (size 1.27 1.27)) (justify left bottom) hide)
    )
    (property "MPN" "PDQE30-Q48-S5-D" (id 5) (at 273.558 117.348 0)
      (effects (font (size 1.27 1.27)) (justify left bottom) hide)
    )
    (property "Manufacturer" "CUI Inc" (id 6) (at 273.558 117.348 0)
      (effects (font (size 1.27 1.27)) (justify left bottom) hide)
    )
    (property "Author" "Antmicro" (id 7) (at 309.118 135.128 0)
      (effects (font (size 1.27 1.27) (thickness 0.15)) (justify left bottom) hide)
    )
    (property "License" "Apache-2.0" (id 8) (at 309.118 137.668 0)
      (effects (font (size 1.27 1.27) (thickness 0.15)) (justify left bottom) hide)
    )
    (pin "1")
    (pin "2")
    (pin "3")
    (pin "4")
    (pin "5")
    (pin "6")
  )

  (symbol (lib_id "sa800u-baseboard-hw:GNDD") (at 251.968 133.858 0) (unit 1)
    (in_bom yes) (on_board yes) (fields_autoplaced)
    (property "Reference" "#PWR0249" (id 0) (at 251.968 140.208 0)
      (effects (font (size 1.27 1.27)) hide)
    )
    (property "Value" "GNDD" (id 1) (at 251.968 138.43 0))
    (property "Footprint" "" (id 2) (at 251.968 133.858 0)
      (effects (font (size 1.27 1.27)) hide)
    )
    (property "Datasheet" "" (id 3) (at 251.968 133.858 0)
      (effects (font (size 1.27 1.27)) hide)
    )
    (property "Author" "Antmicro" (id 4) (at 267.208 141.478 0)
      (effects (font (size 1.27 1.27) (thickness 0.15)) (justify left bottom) hide)
    )
    (property "License" "Apache-2.0" (id 5) (at 267.208 144.018 0)
      (effects (font (size 1.27 1.27) (thickness 0.15)) (justify left bottom) hide)
    )
    (pin "1")
  )

  (symbol (lib_name "C_47u_ELEC_100V_1") (lib_id "sa800u-baseboard-hw:C_47u_ELEC_100V") (at 267.843 123.317 0) (unit 1)
    (in_bom yes) (on_board yes) (fields_autoplaced)
    (property "Reference" "C146" (id 0) (at 265.43 124.0536 0)
      (effects (font (size 1.524 1.524)) (justify right))
    )
    (property "Value" "C_47u_ELEC_100V" (id 1) (at 267.843 127.127 0)
      (effects (font (size 1.524 1.524)) hide)
    )
    (property "Footprint" "sa800u-baseboard-hw-footprints:C_Elec_10x10.5mm" (id 2) (at 272.923 118.237 0)
      (effects (font (size 1.524 1.524)) (justify left) hide)
    )
    (property "Datasheet" "https://industrial.panasonic.com/cdbs/www-data/pdf/RDE0000/ABA0000C1151.pdf" (id 3) (at 267.843 123.317 0)
      (effects (font (size 1.27 1.27)) hide)
    )
    (property "Manufacturer" "Panasonic" (id 4) (at 272.923 113.157 0)
      (effects (font (size 1.524 1.524)) (justify left) hide)
    )
    (property "MPN" "EEEHA2A470UP" (id 5) (at 272.923 115.697 0)
      (effects (font (size 1.524 1.524)) (justify left) hide)
    )
    (property "Val" "47u/100V" (id 6) (at 265.43 127.2285 0)
      (effects (font (size 1.27 1.27)) (justify right))
    )
    (property "License" "Apache-2.0" (id 7) (at 281.813 141.097 0)
      (effects (font (size 1.27 1.27) (thickness 0.15)) (justify left bottom) hide)
    )
    (property "Author" "Antmicro" (id 8) (at 281.813 143.637 0)
      (effects (font (size 1.27 1.27) (thickness 0.15)) (justify left bottom) hide)
    )
    (property "Voltage" "" (id 9) (at 281.813 146.177 0)
      (effects (font (size 1.27 1.27)) (justify left bottom) hide)
    )
    (property "Dielectric" "" (id 10) (at 281.813 148.717 0)
      (effects (font (size 1.27 1.27)) (justify left bottom) hide)
    )
    (pin "1")
    (pin "2")
  )

  (symbol (lib_id "sa800u-baseboard-hw:C_47u_ELEC_100V") (at 251.968 123.317 0) (unit 1)
    (in_bom yes) (on_board yes) (fields_autoplaced)
    (property "Reference" "C145" (id 0) (at 248.92 124.0536 0)
      (effects (font (size 1.524 1.524)) (justify right))
    )
    (property "Value" "C_47u_ELEC_100V" (id 1) (at 251.968 127.127 0)
      (effects (font (size 1.524 1.524)) hide)
    )
    (property "Footprint" "sa800u-baseboard-hw-footprints:C_Elec_10x10.5mm" (id 2) (at 257.048 118.237 0)
      (effects (font (size 1.524 1.524)) (justify left) hide)
    )
    (property "Datasheet" "https://industrial.panasonic.com/cdbs/www-data/pdf/RDE0000/ABA0000C1151.pdf" (id 3) (at 251.968 123.317 0)
      (effects (font (size 1.27 1.27)) hide)
    )
    (property "Manufacturer" "Panasonic" (id 4) (at 257.048 113.157 0)
      (effects (font (size 1.524 1.524)) (justify left) hide)
    )
    (property "MPN" "EEEHA2A470UP" (id 5) (at 257.048 115.697 0)
      (effects (font (size 1.524 1.524)) (justify left) hide)
    )
    (property "Val" "47u/100V" (id 6) (at 248.92 127.2285 0)
      (effects (font (size 1.27 1.27)) (justify right))
    )
    (property "License" "Apache-2.0" (id 7) (at 265.938 141.097 0)
      (effects (font (size 1.27 1.27) (thickness 0.15)) (justify left bottom) hide)
    )
    (property "Author" "Antmicro" (id 8) (at 265.938 143.637 0)
      (effects (font (size 1.27 1.27) (thickness 0.15)) (justify left bottom) hide)
    )
    (property "Voltage" "" (id 9) (at 265.938 146.177 0)
      (effects (font (size 1.27 1.27)) (justify left bottom) hide)
    )
    (property "Dielectric" "" (id 10) (at 265.938 148.717 0)
      (effects (font (size 1.27 1.27)) (justify left bottom) hide)
    )
    (pin "1")
    (pin "2")
  )

  (symbol (lib_id "sa800u-baseboard-hw:GNDD") (at 187.833 145.288 0) (unit 1)
    (in_bom yes) (on_board yes) (fields_autoplaced)
    (property "Reference" "#PWR0245" (id 0) (at 187.833 151.638 0)
      (effects (font (size 1.27 1.27)) hide)
    )
    (property "Value" "GNDD" (id 1) (at 187.833 149.86 0))
    (property "Footprint" "" (id 2) (at 187.833 145.288 0)
      (effects (font (size 1.27 1.27)) hide)
    )
    (property "Datasheet" "" (id 3) (at 187.833 145.288 0)
      (effects (font (size 1.27 1.27)) hide)
    )
    (property "Author" "Antmicro" (id 4) (at 203.073 152.908 0)
      (effects (font (size 1.27 1.27) (thickness 0.15)) (justify left bottom) hide)
    )
    (property "License" "Apache-2.0" (id 5) (at 203.073 155.448 0)
      (effects (font (size 1.27 1.27) (thickness 0.15)) (justify left bottom) hide)
    )
    (pin "1")
  )

  (symbol (lib_id "sa800u-baseboard-hw:R_100k_0402") (at 187.833 132.207 270) (unit 1)
    (in_bom yes) (on_board yes)
    (property "Reference" "R148" (id 0) (at 189.103 133.223 90)
      (effects (font (size 1.524 1.524)) (justify left))
    )
    (property "Value" "R_100k_0402" (id 1) (at 184.023 132.207 0)
      (effects (font (size 1.524 1.524)) hide)
    )
    (property "Footprint" "sa800u-baseboard-hw-footprints:R_0402_1005Metric" (id 2) (at 192.913 137.287 0)
      (effects (font (size 1.524 1.524)) (justify left) hide)
    )
    (property "Datasheet" "https://www.bourns.com/docs/product-datasheets/cr.pdf" (id 3) (at 187.833 132.207 0)
      (effects (font (size 1.27 1.27)) hide)
    )
    (property "Manufacturer" "Bourns" (id 4) (at 197.993 137.287 0)
      (effects (font (size 1.524 1.524)) (justify left) hide)
    )
    (property "MPN" "CR0402-FX-1003GLF" (id 5) (at 195.453 137.287 0)
      (effects (font (size 1.524 1.524)) (justify left) hide)
    )
    (property "Val" "100k" (id 6) (at 189.23 135.636 90)
      (effects (font (size 1.27 1.27)) (justify left))
    )
    (property "DNP" "DNP" (id 7) (at 187.96 132.842 0)
      (effects (font (size 1.27 1.27)) (justify left))
    )
    (property "License" "Apache-2.0" (id 8) (at 162.433 152.527 0)
      (effects (font (size 1.27 1.27) (thickness 0.15)) (justify left bottom) hide)
    )
    (property "Author" "Antmicro" (id 9) (at 159.893 152.527 0)
      (effects (font (size 1.27 1.27) (thickness 0.15)) (justify left bottom) hide)
    )
    (property "Tolerance" "1%" (id 10) (at 177.673 152.527 0)
      (effects (font (size 1.27 1.27)) (justify left bottom) hide)
    )
    (pin "1")
    (pin "2")
  )

  (symbol (lib_id "sa800u-baseboard-hw:R_100k_0402") (at 187.833 121.793 270) (unit 1)
    (in_bom yes) (on_board yes)
    (property "Reference" "R147" (id 0) (at 189.23 122.555 90)
      (effects (font (size 1.524 1.524)) (justify left))
    )
    (property "Value" "R_100k_0402" (id 1) (at 184.023 121.793 0)
      (effects (font (size 1.524 1.524)) hide)
    )
    (property "Footprint" "sa800u-baseboard-hw-footprints:R_0402_1005Metric" (id 2) (at 192.913 126.873 0)
      (effects (font (size 1.524 1.524)) (justify left) hide)
    )
    (property "Datasheet" "https://www.bourns.com/docs/product-datasheets/cr.pdf" (id 3) (at 187.833 121.793 0)
      (effects (font (size 1.27 1.27)) hide)
    )
    (property "Manufacturer" "Bourns" (id 4) (at 197.993 126.873 0)
      (effects (font (size 1.524 1.524)) (justify left) hide)
    )
    (property "MPN" "CR0402-FX-1003GLF" (id 5) (at 195.453 126.873 0)
      (effects (font (size 1.524 1.524)) (justify left) hide)
    )
    (property "Val" "100k" (id 6) (at 189.23 125.7299 90)
      (effects (font (size 1.27 1.27)) (justify left))
    )
    (property "DNP" "DNP" (id 7) (at 187.96 122.301 0)
      (effects (font (size 1.27 1.27)) (justify left))
    )
    (property "License" "Apache-2.0" (id 8) (at 162.433 142.113 0)
      (effects (font (size 1.27 1.27) (thickness 0.15)) (justify left bottom) hide)
    )
    (property "Author" "Antmicro" (id 9) (at 159.893 142.113 0)
      (effects (font (size 1.27 1.27) (thickness 0.15)) (justify left bottom) hide)
    )
    (property "Tolerance" "1%" (id 10) (at 177.673 142.113 0)
      (effects (font (size 1.27 1.27)) (justify left bottom) hide)
    )
    (pin "1")
    (pin "2")
  )

  (symbol (lib_id "sa800u-baseboard-hw:R_0R_0402") (at 180.848 131.318 0) (unit 1)
    (in_bom yes) (on_board yes)
    (property "Reference" "R146" (id 0) (at 183.642 127.381 0)
      (effects (font (size 1.524 1.524)))
    )
    (property "Value" "R_0R_0402" (id 1) (at 180.848 135.128 0)
      (effects (font (size 1.524 1.524)) hide)
    )
    (property "Footprint" "sa800u-baseboard-hw-footprints:R_0402_1005Metric" (id 2) (at 185.928 126.238 0)
      (effects (font (size 1.524 1.524)) (justify left) hide)
    )
    (property "Datasheet" "https://industrial.panasonic.com/cdbs/www-data/pdf/RDA0000/AOA0000C301.pdf" (id 3) (at 180.848 131.318 0)
      (effects (font (size 1.27 1.27)) hide)
    )
    (property "Manufacturer" "Panasonic" (id 4) (at 185.928 121.158 0)
      (effects (font (size 1.524 1.524)) (justify left) hide)
    )
    (property "MPN" "ERJ2GE0R00X" (id 5) (at 185.928 123.698 0)
      (effects (font (size 1.524 1.524)) (justify left) hide)
    )
    (property "Val" "0R" (id 6) (at 183.515 129.159 0))
    (property "License" "Apache-2.0" (id 7) (at 201.168 156.718 0)
      (effects (font (size 1.27 1.27) (thickness 0.15)) (justify left bottom) hide)
    )
    (property "Author" "Antmicro" (id 8) (at 201.168 159.258 0)
      (effects (font (size 1.27 1.27) (thickness 0.15)) (justify left bottom) hide)
    )
    (property "Tolerance" "~" (id 9) (at 201.168 141.478 0)
      (effects (font (size 1.27 1.27)) (justify left bottom) hide)
    )
    (property "Current" "1A" (id 10) (at 201.168 161.798 0)
      (effects (font (size 1.27 1.27) (thickness 0.15)) (justify left bottom) hide)
    )
    (pin "1")
    (pin "2")
  )

  (symbol (lib_id "sa800u-baseboard-hw:R_63R4_0402") (at 139.573 138.43 270) (unit 1)
    (in_bom yes) (on_board yes) (fields_autoplaced)
    (property "Reference" "R144" (id 0) (at 137.16 139.7 90)
      (effects (font (size 1.524 1.524)) (justify right))
    )
    (property "Value" "R_63R4_0402" (id 1) (at 135.763 138.43 0)
      (effects (font (size 1.524 1.524)) hide)
    )
    (property "Footprint" "sa800u-baseboard-hw-footprints:R_0402_1005Metric" (id 2) (at 144.653 143.51 0)
      (effects (font (size 1.524 1.524)) (justify left) hide)
    )
    (property "Datasheet" "https://www.bourns.com/docs/product-datasheets/cr.pdf" (id 3) (at 139.573 138.43 0)
      (effects (font (size 1.27 1.27)) hide)
    )
    (property "Manufacturer" "Bourns" (id 4) (at 149.733 143.51 0)
      (effects (font (size 1.524 1.524)) (justify left) hide)
    )
    (property "MPN" "CR0402-FX-63R4GLF" (id 5) (at 147.193 143.51 0)
      (effects (font (size 1.524 1.524)) (justify left) hide)
    )
    (property "Val" "63R4" (id 6) (at 137.16 142.8749 90)
      (effects (font (size 1.27 1.27)) (justify right))
    )
    (property "License" "Apache-2.0" (id 7) (at 114.173 158.75 0)
      (effects (font (size 1.27 1.27) (thickness 0.15)) (justify left bottom) hide)
    )
    (property "Author" "Antmicro" (id 8) (at 111.633 158.75 0)
      (effects (font (size 1.27 1.27) (thickness 0.15)) (justify left bottom) hide)
    )
    (property "Tolerance" "1%" (id 9) (at 129.413 158.75 0)
      (effects (font (size 1.27 1.27)) (justify left bottom) hide)
    )
    (pin "1")
    (pin "2")
  )

  (symbol (lib_id "sa800u-baseboard-hw:R_24k9_0402") (at 139.573 120.65 270) (unit 1)
    (in_bom yes) (on_board yes) (fields_autoplaced)
    (property "Reference" "R143" (id 0) (at 137.16 121.92 90)
      (effects (font (size 1.524 1.524)) (justify right))
    )
    (property "Value" "R_24k9_0402" (id 1) (at 135.763 120.65 0)
      (effects (font (size 1.524 1.524)) hide)
    )
    (property "Footprint" "sa800u-baseboard-hw-footprints:R_0402_1005Metric" (id 2) (at 144.653 125.73 0)
      (effects (font (size 1.524 1.524)) (justify left) hide)
    )
    (property "Datasheet" "https://www.bourns.com/docs/product-datasheets/cr.pdf" (id 3) (at 139.573 120.65 0)
      (effects (font (size 1.27 1.27)) hide)
    )
    (property "Manufacturer" "Bourns" (id 4) (at 149.733 125.73 0)
      (effects (font (size 1.524 1.524)) (justify left) hide)
    )
    (property "MPN" "CR0402-FX-2492GLF" (id 5) (at 147.193 125.73 0)
      (effects (font (size 1.524 1.524)) (justify left) hide)
    )
    (property "Val" "24k9" (id 6) (at 137.16 125.0949 90)
      (effects (font (size 1.27 1.27)) (justify right))
    )
    (property "License" "Apache-2.0" (id 7) (at 114.173 140.97 0)
      (effects (font (size 1.27 1.27) (thickness 0.15)) (justify left bottom) hide)
    )
    (property "Author" "Antmicro" (id 8) (at 111.633 140.97 0)
      (effects (font (size 1.27 1.27) (thickness 0.15)) (justify left bottom) hide)
    )
    (property "Tolerance" "1%" (id 9) (at 129.413 140.97 0)
      (effects (font (size 1.27 1.27)) (justify left bottom) hide)
    )
    (pin "1")
    (pin "2")
  )

  (symbol (lib_id "sa800u-baseboard-hw:TPS2378DDA") (at 148.463 126.238 0) (unit 1)
    (in_bom yes) (on_board yes) (fields_autoplaced)
    (property "Reference" "IC2" (id 0) (at 158.623 118.11 0))
    (property "Value" "TPS2378DDA" (id 1) (at 158.623 120.65 0))
    (property "Footprint" "sa800u-baseboard-hw-footprints:SOIC-8-1EP_3.9x4.9x1.75mm_P1.27mm" (id 2) (at 170.053 123.698 0)
      (effects (font (size 1.27 1.27)) (justify left) hide)
    )
    (property "Datasheet" "http://www.ti.com/lit/ds/symlink/tps2378.pdf" (id 3) (at 170.053 126.238 0)
      (effects (font (size 1.27 1.27)) (justify left) hide)
    )
    (property "Description" "IEEE 802.3at PoE High-Power PD Interface with AUX Control" (id 4) (at 170.053 128.778 0)
      (effects (font (size 1.27 1.27)) (justify left) hide)
    )
    (property "Manufacturer" "Texas Instruments" (id 5) (at 170.053 133.858 0)
      (effects (font (size 1.27 1.27)) (justify left) hide)
    )
    (property "MPN" "TPS2378DDA" (id 6) (at 170.053 136.398 0)
      (effects (font (size 1.27 1.27)) (justify left) hide)
    )
    (property "Arrow Part Number" "TPS2378DDA" (id 7) (at 170.053 138.938 0)
      (effects (font (size 1.27 1.27)) (justify left) hide)
    )
    (property "Arrow Price/Stock" "https://www.arrow.com/en/products/tps2378dda/texas-instruments" (id 8) (at 170.053 141.478 0)
      (effects (font (size 1.27 1.27)) (justify left) hide)
    )
    (property "Mouser Part Number" "595-TPS2378DDA" (id 9) (at 170.053 144.018 0)
      (effects (font (size 1.27 1.27)) (justify left) hide)
    )
    (property "Mouser Price/Stock" "https://www.mouser.co.uk/ProductDetail/Texas-Instruments/TPS2378DDA?qs=5771e39Rz9HhOSwUvwIrNw%3D%3D" (id 10) (at 170.053 146.558 0)
      (effects (font (size 1.27 1.27)) (justify left) hide)
    )
    (property "Author" "Antmicro" (id 11) (at 184.023 141.478 0)
      (effects (font (size 1.27 1.27) (thickness 0.15)) (justify left bottom) hide)
    )
    (property "License" "Apache-2.0" (id 12) (at 184.023 144.018 0)
      (effects (font (size 1.27 1.27) (thickness 0.15)) (justify left bottom) hide)
    )
    (pin "1")
    (pin "2")
    (pin "3")
    (pin "4")
    (pin "5")
    (pin "6")
    (pin "7")
    (pin "8")
    (pin "9")
  )

  (symbol (lib_id "sa800u-baseboard-hw:C_100n_0805_100V") (at 123.19 129.286 270) (unit 1)
    (in_bom yes) (on_board yes)
    (property "Reference" "C144" (id 0) (at 124.333 132.207 0)
      (effects (font (size 1.524 1.524)) (justify left))
    )
    (property "Value" "C_100n_0805_100V" (id 1) (at 121.8438 132.207 0)
      (effects (font (size 1.524 1.524)) (justify left) hide)
    )
    (property "Footprint" "sa800u-baseboard-hw-footprints:C_0805_2012Metric" (id 2) (at 128.27 134.366 0)
      (effects (font (size 1.524 1.524)) (justify left) hide)
    )
    (property "Datasheet" "https://www.mouser.pl/datasheet/2/585/MLCC-1837944.pdf" (id 3) (at 123.19 129.286 0)
      (effects (font (size 1.27 1.27)) hide)
    )
    (property "Manufacturer" "SAMSUNG" (id 4) (at 133.35 134.366 0)
      (effects (font (size 1.524 1.524)) (justify left) hide)
    )
    (property "MPN" "CL21B104KCFNNNE" (id 5) (at 130.81 134.366 0)
      (effects (font (size 1.524 1.524)) (justify left) hide)
    )
    (property "Val" "100n/100V" (id 6) (at 121.8438 132.207 0)
      (effects (font (size 1.27 1.27)) (justify left))
    )
    (property "License" "Apache-2.0" (id 7) (at 100.33 149.606 0)
      (effects (font (size 1.27 1.27) (thickness 0.15)) (justify left bottom) hide)
    )
    (property "Author" "Antmicro" (id 8) (at 97.79 149.606 0)
      (effects (font (size 1.27 1.27) (thickness 0.15)) (justify left bottom) hide)
    )
    (property "Voltage" "100V" (id 9) (at 95.25 149.606 0)
      (effects (font (size 1.27 1.27)) (justify left bottom) hide)
    )
    (property "Dielectric" "X7R" (id 10) (at 92.71 149.606 0)
      (effects (font (size 1.27 1.27)) (justify left bottom) hide)
    )
    (pin "1")
    (pin "2")
  )

  (symbol (lib_id "sa800u-baseboard-hw:SMAJ58A-13-F") (at 117.856 136.398 90) (unit 1)
    (in_bom yes) (on_board yes)
    (property "Reference" "D31" (id 0) (at 115.57 130.81 90)
      (effects (font (size 1.524 1.524)) (justify left))
    )
    (property "Value" "SMAJ58A-13-F" (id 1) (at 115.57 133.5024 90)
      (effects (font (size 1.524 1.524)) (justify left))
    )
    (property "Footprint" "sa800u-baseboard-hw-footprints:DO-214AC" (id 2) (at 112.776 131.318 0)
      (effects (font (size 1.524 1.524)) (justify left) hide)
    )
    (property "Datasheet" "https://4donline.ihs.com/images/VipMasterIC/IC/DIOD/DIOD-S-A0001754755/DIOD-S-A0001754755-1.pdf?hkey=52A5661711E402568146F3353EA87419" (id 3) (at 110.236 131.318 0)
      (effects (font (size 1.524 1.524)) (justify left) hide)
    )
    (property "MPN" "SMAJ58A-13-F" (id 4) (at 105.156 131.318 0)
      (effects (font (size 1.524 1.524)) (justify left) hide)
    )
    (property "Manufacturer" "Diodes Incorporated" (id 5) (at 89.916 131.318 0)
      (effects (font (size 1.524 1.524)) (justify left) hide)
    )
    (property "Author" "Antmicro" (id 6) (at 138.176 114.808 0)
      (effects (font (size 1.27 1.27) (thickness 0.15)) (justify left bottom) hide)
    )
    (property "License" "Apache-2.0" (id 7) (at 140.716 114.808 0)
      (effects (font (size 1.27 1.27) (thickness 0.15)) (justify left bottom) hide)
    )
    (pin "A")
    (pin "K")
  )

  (symbol (lib_id "sa800u-baseboard-hw:FB_220Z_2A_0805") (at 102.87 146.558 0) (unit 1)
    (in_bom yes) (on_board yes)
    (property "Reference" "FB5" (id 0) (at 105.41 149.606 0)
      (effects (font (size 1.524 1.524)))
    )
    (property "Value" "FB_220Z_2A_0805" (id 1) (at 104.902 152.019 0)
      (effects (font (size 1.524 1.524)))
    )
    (property "Footprint" "sa800u-baseboard-hw-footprints:FB_0805_2012Metric" (id 2) (at 107.95 141.478 0)
      (effects (font (size 1.524 1.524)) (justify left) hide)
    )
    (property "Datasheet" "https://www.murata.com/products/productdata/8796738977822/ENFA0005.pdf?1653276712000" (id 3) (at 107.95 138.938 0)
      (effects (font (size 1.524 1.524)) (justify left) hide)
    )
    (property "MPN" "BLM21PG221SN1D" (id 4) (at 102.87 139.2682 0)
      (effects (font (size 1.524 1.524)) hide)
    )
    (property "Manufacturer" "Murata" (id 5) (at 102.87 141.9606 0)
      (effects (font (size 1.524 1.524)) hide)
    )
    (property "Author" "Antmicro" (id 6) (at 116.84 161.798 0)
      (effects (font (size 1.27 1.27) (thickness 0.15)) (justify left bottom) hide)
    )
    (property "License" "Apache-2.0" (id 7) (at 116.84 164.338 0)
      (effects (font (size 1.27 1.27) (thickness 0.15)) (justify left bottom) hide)
    )
    (pin "1")
    (pin "2")
  )

  (symbol (lib_id "sa800u-baseboard-hw:FB_220Z_2A_0805") (at 102.235 117.348 0) (unit 1)
    (in_bom yes) (on_board yes)
    (property "Reference" "FB4" (id 0) (at 102.235 110.0582 0)
      (effects (font (size 1.524 1.524)))
    )
    (property "Value" "FB_220Z_2A_0805" (id 1) (at 102.235 112.7506 0)
      (effects (font (size 1.524 1.524)))
    )
    (property "Footprint" "sa800u-baseboard-hw-footprints:FB_0805_2012Metric" (id 2) (at 107.315 112.268 0)
      (effects (font (size 1.524 1.524)) (justify left) hide)
    )
    (property "Datasheet" "https://www.murata.com/products/productdata/8796738977822/ENFA0005.pdf?1653276712000" (id 3) (at 107.315 109.728 0)
      (effects (font (size 1.524 1.524)) (justify left) hide)
    )
    (property "MPN" "BLM21PG221SN1D" (id 4) (at 102.235 110.0582 0)
      (effects (font (size 1.524 1.524)) hide)
    )
    (property "Manufacturer" "Murata" (id 5) (at 102.235 112.7506 0)
      (effects (font (size 1.524 1.524)) hide)
    )
    (property "Author" "Antmicro" (id 6) (at 116.205 132.588 0)
      (effects (font (size 1.27 1.27) (thickness 0.15)) (justify left bottom) hide)
    )
    (property "License" "Apache-2.0" (id 7) (at 116.205 135.128 0)
      (effects (font (size 1.27 1.27) (thickness 0.15)) (justify left bottom) hide)
    )
    (pin "1")
    (pin "2")
  )

  (symbol (lib_name "MB10S_1") (lib_id "sa800u-baseboard-hw:MB10S") (at 67.818 138.938 0) (unit 1)
    (in_bom yes) (on_board yes)
    (property "Reference" "D30" (id 0) (at 76.708 133.223 0))
    (property "Value" "MB10S" (id 1) (at 76.708 135.5344 0))
    (property "Footprint" "sa800u-baseboard-hw-footprints:SOIC-4_4.2x5.0mm_P5.7mm" (id 2) (at 53.848 140.208 0)
      (effects (font (size 1.27 1.27)) hide)
    )
    (property "Datasheet" "http://www.farnell.com/datasheets/2895435.pdf" (id 3) (at 53.848 140.208 0)
      (effects (font (size 1.27 1.27)) hide)
    )
    (property "MPN" "MB10S" (id 4) (at 76.708 133.223 0)
      (effects (font (size 1.27 1.27)) hide)
    )
    (property "Manufacturer" "Multicomp" (id 5) (at 76.708 135.5344 0)
      (effects (font (size 1.27 1.27)) hide)
    )
    (property "Author" "Antmicro" (id 6) (at 95.758 156.718 0)
      (effects (font (size 1.27 1.27) (thickness 0.15)) (justify left bottom) hide)
    )
    (property "License" "Apache-2.0" (id 7) (at 95.758 159.258 0)
      (effects (font (size 1.27 1.27) (thickness 0.15)) (justify left bottom) hide)
    )
    (pin "1")
    (pin "2")
    (pin "3")
    (pin "4")
  )

  (symbol (lib_id "sa800u-baseboard-hw:MB10S") (at 67.818 112.268 0) (unit 1)
    (in_bom yes) (on_board yes)
    (property "Reference" "D29" (id 0) (at 76.708 106.553 0))
    (property "Value" "MB10S" (id 1) (at 76.708 108.8644 0))
    (property "Footprint" "sa800u-baseboard-hw-footprints:SOIC-4_4.2x5.0mm_P5.7mm" (id 2) (at 53.848 113.538 0)
      (effects (font (size 1.27 1.27)) hide)
    )
    (property "Datasheet" "http://www.farnell.com/datasheets/2895435.pdf" (id 3) (at 53.848 113.538 0)
      (effects (font (size 1.27 1.27)) hide)
    )
    (property "MPN" "MB10S" (id 4) (at 76.708 106.553 0)
      (effects (font (size 1.27 1.27)) hide)
    )
    (property "Manufacturer" "Multicomp" (id 5) (at 76.708 108.8644 0)
      (effects (font (size 1.27 1.27)) hide)
    )
    (property "Author" "Antmicro" (id 6) (at 95.758 130.048 0)
      (effects (font (size 1.27 1.27) (thickness 0.15)) (justify left bottom) hide)
    )
    (property "License" "Apache-2.0" (id 7) (at 95.758 132.588 0)
      (effects (font (size 1.27 1.27) (thickness 0.15)) (justify left bottom) hide)
    )
    (pin "1")
    (pin "2")
    (pin "3")
    (pin "4")
  )

  (symbol (lib_id "sa800u-baseboard-hw:R_0R_0402") (at 180.213 142.748 90) (unit 1)
    (in_bom yes) (on_board yes)
    (property "Reference" "R145" (id 0) (at 181.356 138.811 90)
      (effects (font (size 1.524 1.524)) (justify right))
    )
    (property "Value" "R_0R_0402" (id 1) (at 184.023 142.748 0)
      (effects (font (size 1.524 1.524)) hide)
    )
    (property "Footprint" "sa800u-baseboard-hw-footprints:R_0402_1005Metric" (id 2) (at 175.133 137.668 0)
      (effects (font (size 1.524 1.524)) (justify left) hide)
    )
    (property "Datasheet" "https://industrial.panasonic.com/cdbs/www-data/pdf/RDA0000/AOA0000C301.pdf" (id 3) (at 180.213 142.748 0)
      (effects (font (size 1.27 1.27)) hide)
    )
    (property "Manufacturer" "Panasonic" (id 4) (at 170.053 137.668 0)
      (effects (font (size 1.524 1.524)) (justify left) hide)
    )
    (property "MPN" "ERJ2GE0R00X" (id 5) (at 172.593 137.668 0)
      (effects (font (size 1.524 1.524)) (justify left) hide)
    )
    (property "Val" "0R" (id 6) (at 181.737 141.478 90)
      (effects (font (size 1.27 1.27)) (justify right))
    )
    (property "License" "Apache-2.0" (id 7) (at 205.613 122.428 0)
      (effects (font (size 1.27 1.27) (thickness 0.15)) (justify left bottom) hide)
    )
    (property "Author" "Antmicro" (id 8) (at 208.153 122.428 0)
      (effects (font (size 1.27 1.27) (thickness 0.15)) (justify left bottom) hide)
    )
    (property "Tolerance" "~" (id 9) (at 190.373 122.428 0)
      (effects (font (size 1.27 1.27)) (justify left bottom) hide)
    )
    (property "Current" "1A" (id 10) (at 210.693 122.428 0)
      (effects (font (size 1.27 1.27) (thickness 0.15)) (justify left bottom) hide)
    )
    (pin "1")
    (pin "2")
  )

  (symbol (lib_id "sa800u-baseboard-hw:GNDD") (at 180.213 145.288 0) (unit 1)
    (in_bom yes) (on_board yes) (fields_autoplaced)
    (property "Reference" "#PWR0244" (id 0) (at 180.213 151.638 0)
      (effects (font (size 1.27 1.27)) hide)
    )
    (property "Value" "GNDD" (id 1) (at 180.213 149.86 0))
    (property "Footprint" "" (id 2) (at 180.213 145.288 0)
      (effects (font (size 1.27 1.27)) hide)
    )
    (property "Datasheet" "" (id 3) (at 180.213 145.288 0)
      (effects (font (size 1.27 1.27)) hide)
    )
    (property "Author" "Antmicro" (id 4) (at 195.453 152.908 0)
      (effects (font (size 1.27 1.27) (thickness 0.15)) (justify left bottom) hide)
    )
    (property "License" "Apache-2.0" (id 5) (at 195.453 155.448 0)
      (effects (font (size 1.27 1.27) (thickness 0.15)) (justify left bottom) hide)
    )
    (pin "1")
  )

  (symbol (lib_id "sa800u-baseboard-hw:GNDD") (at 172.593 145.288 0) (unit 1)
    (in_bom yes) (on_board yes) (fields_autoplaced)
    (property "Reference" "#PWR0243" (id 0) (at 172.593 151.638 0)
      (effects (font (size 1.27 1.27)) hide)
    )
    (property "Value" "GNDD" (id 1) (at 172.593 149.86 0))
    (property "Footprint" "" (id 2) (at 172.593 145.288 0)
      (effects (font (size 1.27 1.27)) hide)
    )
    (property "Datasheet" "" (id 3) (at 172.593 145.288 0)
      (effects (font (size 1.27 1.27)) hide)
    )
    (property "Author" "Antmicro" (id 4) (at 187.833 152.908 0)
      (effects (font (size 1.27 1.27) (thickness 0.15)) (justify left bottom) hide)
    )
    (property "License" "Apache-2.0" (id 5) (at 187.833 155.448 0)
      (effects (font (size 1.27 1.27) (thickness 0.15)) (justify left bottom) hide)
    )
    (pin "1")
  )

  (symbol (lib_id "sa800u-baseboard-hw:R_20k_0603") (at 217.678 119.253 270) (unit 1)
    (in_bom yes) (on_board yes) (fields_autoplaced)
    (property "Reference" "R149" (id 0) (at 215.9 120.523 90)
      (effects (font (size 1.524 1.524)) (justify right))
    )
    (property "Value" "R_20k_0603" (id 1) (at 213.868 119.253 0)
      (effects (font (size 1.524 1.524)) hide)
    )
    (property "Footprint" "sa800u-baseboard-hw-footprints:R_0603_1608Metric" (id 2) (at 222.758 124.333 0)
      (effects (font (size 1.524 1.524)) (justify left) hide)
    )
    (property "Datasheet" "https://www.bourns.com/docs/product-datasheets/cr.pdf" (id 3) (at 217.678 119.253 0)
      (effects (font (size 1.27 1.27)) hide)
    )
    (property "Manufacturer" "Bourns" (id 4) (at 227.838 124.333 0)
      (effects (font (size 1.524 1.524)) (justify left) hide)
    )
    (property "MPN" "CR0603-FX-2002ELF" (id 5) (at 225.298 124.333 0)
      (effects (font (size 1.524 1.524)) (justify left) hide)
    )
    (property "Val" "20k" (id 6) (at 215.9 123.6979 90)
      (effects (font (size 1.27 1.27)) (justify right))
    )
    (property "License" "Apache-2.0" (id 7) (at 192.278 139.573 0)
      (effects (font (size 1.27 1.27) (thickness 0.15)) (justify left bottom) hide)
    )
    (property "Author" "Antmicro" (id 8) (at 189.738 139.573 0)
      (effects (font (size 1.27 1.27) (thickness 0.15)) (justify left bottom) hide)
    )
    (property "Tolerance" "1%" (id 9) (at 207.518 139.573 0)
      (effects (font (size 1.27 1.27)) (justify left bottom) hide)
    )
    (pin "1")
    (pin "2")
  )

  (symbol (lib_id "sa800u-baseboard-hw:R_10k_0603") (at 217.678 129.413 270) (unit 1)
    (in_bom yes) (on_board yes)
    (property "Reference" "R150" (id 0) (at 219.71 129.413 90)
      (effects (font (size 1.524 1.524)) (justify left))
    )
    (property "Value" "R_10k_0603" (id 1) (at 213.868 129.413 0)
      (effects (font (size 1.524 1.524)) hide)
    )
    (property "Footprint" "sa800u-baseboard-hw-footprints:R_0603_1608Metric" (id 2) (at 222.758 134.493 0)
      (effects (font (size 1.524 1.524)) (justify left) hide)
    )
    (property "Datasheet" "https://www.bourns.com/docs/product-datasheets/cr.pdf" (id 3) (at 217.678 129.413 0)
      (effects (font (size 1.27 1.27)) hide)
    )
    (property "Manufacturer" "Bourns" (id 4) (at 227.838 134.493 0)
      (effects (font (size 1.524 1.524)) (justify left) hide)
    )
    (property "MPN" "CR0603-FX-1002ELF" (id 5) (at 225.298 134.493 0)
      (effects (font (size 1.524 1.524)) (justify left) hide)
    )
    (property "Val" "10k" (id 6) (at 219.71 132.5879 90)
      (effects (font (size 1.27 1.27)) (justify left))
    )
    (property "DNP" "DNP" (id 7) (at 217.805 130.048 0)
      (effects (font (size 1.27 1.27)) (justify left))
    )
    (property "License" "Apache-2.0" (id 8) (at 192.278 149.733 0)
      (effects (font (size 1.27 1.27) (thickness 0.15)) (justify left bottom) hide)
    )
    (property "Author" "Antmicro" (id 9) (at 189.738 149.733 0)
      (effects (font (size 1.27 1.27) (thickness 0.15)) (justify left bottom) hide)
    )
    (property "Tolerance" "1%" (id 10) (at 207.518 149.733 0)
      (effects (font (size 1.27 1.27)) (justify left bottom) hide)
    )
    (pin "1")
    (pin "2")
  )

  (symbol (lib_id "sa800u-baseboard-hw:GNDD") (at 217.678 136.398 0) (unit 1)
    (in_bom yes) (on_board yes) (fields_autoplaced)
    (property "Reference" "#PWR0247" (id 0) (at 217.678 142.748 0)
      (effects (font (size 1.27 1.27)) hide)
    )
    (property "Value" "GNDD" (id 1) (at 214.63 137.4139 0)
      (effects (font (size 1.27 1.27)) (justify right))
    )
    (property "Footprint" "" (id 2) (at 217.678 136.398 0)
      (effects (font (size 1.27 1.27)) hide)
    )
    (property "Datasheet" "" (id 3) (at 217.678 136.398 0)
      (effects (font (size 1.27 1.27)) hide)
    )
    (property "Author" "Antmicro" (id 4) (at 232.918 144.018 0)
      (effects (font (size 1.27 1.27) (thickness 0.15)) (justify left bottom) hide)
    )
    (property "License" "Apache-2.0" (id 5) (at 232.918 146.558 0)
      (effects (font (size 1.27 1.27) (thickness 0.15)) (justify left bottom) hide)
    )
    (pin "1")
  )

  (symbol (lib_id "sa800u-baseboard-hw:LED_G_0603_KP-1608ZGC") (at 227.838 128.778 270) (unit 1)
    (in_bom yes) (on_board yes) (fields_autoplaced)
    (property "Reference" "D32" (id 0) (at 231.14 131.318 90)
      (effects (font (size 1.524 1.524)) (justify left))
    )
    (property "Value" "KP-1608EC" (id 1) (at 232.3592 128.8542 90)
      (effects (font (size 1.524 1.524)) (justify left) hide)
    )
    (property "Footprint" "sa800u-baseboard-hw-footprints:LED_0603_1608Metric_G" (id 2) (at 217.678 151.638 0)
      (effects (font (size 1.27 1.27) (thickness 0.15)) (justify left bottom) hide)
    )
    (property "Datasheet" "https://www.farnell.com/datasheets/2045914.pdf" (id 3) (at 215.138 151.638 0)
      (effects (font (size 1.27 1.27) (thickness 0.15)) (justify left bottom) hide)
    )
    (property "MPN" "KP-1608ZGC" (id 4) (at 212.598 151.638 0)
      (effects (font (size 1.27 1.27) (thickness 0.15)) (justify left bottom) hide)
    )
    (property "Manufacturer" "Kingbright" (id 5) (at 210.058 151.638 0)
      (effects (font (size 1.27 1.27) (thickness 0.15)) (justify left bottom) hide)
    )
    (property "Author" "Antmicro" (id 6) (at 207.518 151.638 0)
      (effects (font (size 1.27 1.27) (thickness 0.15)) (justify left bottom) hide)
    )
    (property "License" "Apache-2.0" (id 7) (at 204.978 151.638 0)
      (effects (font (size 1.27 1.27) (thickness 0.15)) (justify left bottom) hide)
    )
    (pin "1")
    (pin "2")
  )

  (symbol (lib_id "sa800u-baseboard-hw:GNDD") (at 227.838 136.398 0) (unit 1)
    (in_bom yes) (on_board yes) (fields_autoplaced)
    (property "Reference" "#PWR0248" (id 0) (at 227.838 142.748 0)
      (effects (font (size 1.27 1.27)) hide)
    )
    (property "Value" "GNDD" (id 1) (at 227.838 140.97 0))
    (property "Footprint" "" (id 2) (at 227.838 136.398 0)
      (effects (font (size 1.27 1.27)) hide)
    )
    (property "Datasheet" "" (id 3) (at 227.838 136.398 0)
      (effects (font (size 1.27 1.27)) hide)
    )
    (property "Author" "Antmicro" (id 4) (at 243.078 144.018 0)
      (effects (font (size 1.27 1.27) (thickness 0.15)) (justify left bottom) hide)
    )
    (property "License" "Apache-2.0" (id 5) (at 243.078 146.558 0)
      (effects (font (size 1.27 1.27) (thickness 0.15)) (justify left bottom) hide)
    )
    (pin "1")
  )

  (symbol (lib_id "sa800u-baseboard-hw:PWR_FLAG") (at 368.808 117.348 0) (unit 1)
    (in_bom yes) (on_board yes) (fields_autoplaced)
    (property "Reference" "#FLG027" (id 0) (at 368.808 115.443 0)
      (effects (font (size 1.27 1.27)) hide)
    )
    (property "Value" "PWR_FLAG" (id 1) (at 368.808 111.76 0))
    (property "Footprint" "" (id 2) (at 368.808 117.348 0)
      (effects (font (size 1.27 1.27)) hide)
    )
    (property "Datasheet" "~" (id 3) (at 368.808 117.348 0)
      (effects (font (size 1.27 1.27)) hide)
    )
    (pin "1")
  )

  (symbol (lib_id "sa800u-baseboard-hw:C_100u_0805") (at 333.248 118.618 270) (unit 1)
    (in_bom yes) (on_board yes) (fields_autoplaced)
    (property "Reference" "C148" (id 0) (at 336.677 119.8943 90)
      (effects (font (size 1.524 1.524)) (justify left))
    )
    (property "Value" "C_100u_0805" (id 1) (at 329.438 118.618 0)
      (effects (font (size 1.524 1.524)) hide)
    )
    (property "Footprint" "sa800u-baseboard-hw-footprints:C_0805_2012Metric" (id 2) (at 338.328 123.698 0)
      (effects (font (size 1.524 1.524)) (justify left) hide)
    )
    (property "Datasheet" " " (id 3) (at 333.248 118.618 0)
      (effects (font (size 1.27 1.27)) hide)
    )
    (property "Manufacturer" "Murata" (id 4) (at 343.408 123.698 0)
      (effects (font (size 1.524 1.524)) (justify left) hide)
    )
    (property "MPN" "GRM21BR60J107ME15L" (id 5) (at 340.868 123.698 0)
      (effects (font (size 1.524 1.524)) (justify left) hide)
    )
    (property "Val" "100u" (id 6) (at 336.677 123.0692 90)
      (effects (font (size 1.27 1.27)) (justify left))
    )
    (property "License" "Apache-2.0" (id 7) (at 310.388 138.938 0)
      (effects (font (size 1.27 1.27) (thickness 0.15)) (justify left bottom) hide)
    )
    (property "Author" "Antmicro" (id 8) (at 307.848 138.938 0)
      (effects (font (size 1.27 1.27) (thickness 0.15)) (justify left bottom) hide)
    )
    (property "Voltage" "" (id 9) (at 305.308 138.938 0)
      (effects (font (size 1.27 1.27)) (justify left bottom) hide)
    )
    (property "Dielectric" "" (id 10) (at 302.768 138.938 0)
      (effects (font (size 1.27 1.27)) (justify left bottom) hide)
    )
    (pin "1")
    (pin "2")
  )

  (symbol (lib_id "sa800u-baseboard-hw:C_100u_0805") (at 320.548 118.618 270) (unit 1)
    (in_bom yes) (on_board yes) (fields_autoplaced)
    (property "Reference" "C147" (id 0) (at 323.469 119.8943 90)
      (effects (font (size 1.524 1.524)) (justify left))
    )
    (property "Value" "C_100u_0805" (id 1) (at 316.738 118.618 0)
      (effects (font (size 1.524 1.524)) hide)
    )
    (property "Footprint" "sa800u-baseboard-hw-footprints:C_0805_2012Metric" (id 2) (at 325.628 123.698 0)
      (effects (font (size 1.524 1.524)) (justify left) hide)
    )
    (property "Datasheet" " " (id 3) (at 320.548 118.618 0)
      (effects (font (size 1.27 1.27)) hide)
    )
    (property "Manufacturer" "Murata" (id 4) (at 330.708 123.698 0)
      (effects (font (size 1.524 1.524)) (justify left) hide)
    )
    (property "MPN" "GRM21BR60J107ME15L" (id 5) (at 328.168 123.698 0)
      (effects (font (size 1.524 1.524)) (justify left) hide)
    )
    (property "Val" "100u" (id 6) (at 323.469 123.0692 90)
      (effects (font (size 1.27 1.27)) (justify left))
    )
    (property "License" "Apache-2.0" (id 7) (at 297.688 138.938 0)
      (effects (font (size 1.27 1.27) (thickness 0.15)) (justify left bottom) hide)
    )
    (property "Author" "Antmicro" (id 8) (at 295.148 138.938 0)
      (effects (font (size 1.27 1.27) (thickness 0.15)) (justify left bottom) hide)
    )
    (property "Voltage" "" (id 9) (at 292.608 138.938 0)
      (effects (font (size 1.27 1.27)) (justify left bottom) hide)
    )
    (property "Dielectric" "" (id 10) (at 290.068 138.938 0)
      (effects (font (size 1.27 1.27)) (justify left bottom) hide)
    )
    (pin "1")
    (pin "2")
  )

  (symbol (lib_id "sa800u-baseboard-hw:TP_0.75mm_SMD") (at 337.312 133.985 270) (unit 1)
    (in_bom yes) (on_board yes) (fields_autoplaced)
    (property "Reference" "TP85" (id 0) (at 338.836 137.1599 90)
      (effects (font (size 1.27 1.27)) (justify left))
    )
    (property "Value" "TP_0.75mm_SMD" (id 1) (at 337.312 133.985 0)
      (effects (font (size 1.27 1.27)) hide)
    )
    (property "Footprint" "sa800u-baseboard-hw-footprints:TP_SMD_0.75mm" (id 2) (at 337.312 133.985 0)
      (effects (font (size 1.27 1.27)) hide)
    )
    (property "Datasheet" "" (id 3) (at 337.312 133.985 0)
      (effects (font (size 1.27 1.27)) hide)
    )
    (property "MPN" "" (id 4) (at 322.072 151.765 0)
      (effects (font (size 1.27 1.27) (thickness 0.15)) (justify left bottom) hide)
    )
    (property "Manufacturer" "" (id 5) (at 319.532 151.765 0)
      (effects (font (size 1.27 1.27) (thickness 0.15)) (justify left bottom) hide)
    )
    (property "Author" "Antmicro" (id 6) (at 316.992 151.765 0)
      (effects (font (size 1.27 1.27) (thickness 0.15)) (justify left bottom) hide)
    )
    (property "License" "Apache-2.0" (id 7) (at 314.452 151.765 0)
      (effects (font (size 1.27 1.27) (thickness 0.15)) (justify left bottom) hide)
    )
    (pin "1")
  )

  (symbol (lib_id "sa800u-baseboard-hw:TP_0.75mm_SMD") (at 336.423 115.824 90) (unit 1)
    (in_bom yes) (on_board yes) (fields_autoplaced)
    (property "Reference" "TP84" (id 0) (at 338.963 112.6489 90)
      (effects (font (size 1.27 1.27)) (justify right))
    )
    (property "Value" "TP_0.75mm_SMD" (id 1) (at 336.423 115.824 0)
      (effects (font (size 1.27 1.27)) hide)
    )
    (property "Footprint" "sa800u-baseboard-hw-footprints:TP_SMD_0.75mm" (id 2) (at 336.423 115.824 0)
      (effects (font (size 1.27 1.27)) hide)
    )
    (property "Datasheet" "" (id 3) (at 336.423 115.824 0)
      (effects (font (size 1.27 1.27)) hide)
    )
    (property "MPN" "" (id 4) (at 351.663 98.044 0)
      (effects (font (size 1.27 1.27) (thickness 0.15)) (justify left bottom) hide)
    )
    (property "Manufacturer" "" (id 5) (at 354.203 98.044 0)
      (effects (font (size 1.27 1.27) (thickness 0.15)) (justify left bottom) hide)
    )
    (property "Author" "Antmicro" (id 6) (at 356.743 98.044 0)
      (effects (font (size 1.27 1.27) (thickness 0.15)) (justify left bottom) hide)
    )
    (property "License" "Apache-2.0" (id 7) (at 359.283 98.044 0)
      (effects (font (size 1.27 1.27) (thickness 0.15)) (justify left bottom) hide)
    )
    (pin "1")
  )

  (symbol (lib_id "sa800u-baseboard-hw:TP_0.75mm_SMD") (at 307.848 124.968 0) (unit 1)
    (in_bom yes) (on_board yes) (fields_autoplaced)
    (property "Reference" "TP83" (id 0) (at 311.023 121.92 0))
    (property "Value" "TP_0.75mm_SMD" (id 1) (at 307.848 124.968 0)
      (effects (font (size 1.27 1.27)) hide)
    )
    (property "Footprint" "sa800u-baseboard-hw-footprints:TP_SMD_0.75mm" (id 2) (at 307.848 124.968 0)
      (effects (font (size 1.27 1.27)) hide)
    )
    (property "Datasheet" "" (id 3) (at 307.848 124.968 0)
      (effects (font (size 1.27 1.27)) hide)
    )
    (property "MPN" "" (id 4) (at 325.628 140.208 0)
      (effects (font (size 1.27 1.27) (thickness 0.15)) (justify left bottom) hide)
    )
    (property "Manufacturer" "" (id 5) (at 325.628 142.748 0)
      (effects (font (size 1.27 1.27) (thickness 0.15)) (justify left bottom) hide)
    )
    (property "Author" "Antmicro" (id 6) (at 325.628 145.288 0)
      (effects (font (size 1.27 1.27) (thickness 0.15)) (justify left bottom) hide)
    )
    (property "License" "Apache-2.0" (id 7) (at 325.628 147.828 0)
      (effects (font (size 1.27 1.27) (thickness 0.15)) (justify left bottom) hide)
    )
    (pin "1")
  )

  (symbol (lib_id "sa800u-baseboard-hw:TP_0.75mm_SMD") (at 271.018 104.267 90) (unit 1)
    (in_bom yes) (on_board yes) (fields_autoplaced)
    (property "Reference" "TP82" (id 0) (at 273.05 101.0919 90)
      (effects (font (size 1.27 1.27)) (justify right))
    )
    (property "Value" "TP_0.75mm_SMD" (id 1) (at 271.018 104.267 0)
      (effects (font (size 1.27 1.27)) hide)
    )
    (property "Footprint" "sa800u-baseboard-hw-footprints:TP_SMD_0.75mm" (id 2) (at 271.018 104.267 0)
      (effects (font (size 1.27 1.27)) hide)
    )
    (property "Datasheet" "" (id 3) (at 271.018 104.267 0)
      (effects (font (size 1.27 1.27)) hide)
    )
    (property "MPN" "" (id 4) (at 286.258 86.487 0)
      (effects (font (size 1.27 1.27) (thickness 0.15)) (justify left bottom) hide)
    )
    (property "Manufacturer" "" (id 5) (at 288.798 86.487 0)
      (effects (font (size 1.27 1.27) (thickness 0.15)) (justify left bottom) hide)
    )
    (property "Author" "Antmicro" (id 6) (at 291.338 86.487 0)
      (effects (font (size 1.27 1.27) (thickness 0.15)) (justify left bottom) hide)
    )
    (property "License" "Apache-2.0" (id 7) (at 293.878 86.487 0)
      (effects (font (size 1.27 1.27) (thickness 0.15)) (justify left bottom) hide)
    )
    (pin "1")
  )

  (symbol (lib_id "sa800u-baseboard-hw:TP_0.75mm_SMD") (at 123.19 116.078 90) (unit 1)
    (in_bom yes) (on_board yes) (fields_autoplaced)
    (property "Reference" "TP78" (id 0) (at 125.73 112.9029 90)
      (effects (font (size 1.27 1.27)) (justify right))
    )
    (property "Value" "TP_0.75mm_SMD" (id 1) (at 123.19 116.078 0)
      (effects (font (size 1.27 1.27)) hide)
    )
    (property "Footprint" "sa800u-baseboard-hw-footprints:TP_SMD_0.75mm" (id 2) (at 123.19 116.078 0)
      (effects (font (size 1.27 1.27)) hide)
    )
    (property "Datasheet" "" (id 3) (at 123.19 116.078 0)
      (effects (font (size 1.27 1.27)) hide)
    )
    (property "MPN" "" (id 4) (at 138.43 98.298 0)
      (effects (font (size 1.27 1.27) (thickness 0.15)) (justify left bottom) hide)
    )
    (property "Manufacturer" "" (id 5) (at 140.97 98.298 0)
      (effects (font (size 1.27 1.27) (thickness 0.15)) (justify left bottom) hide)
    )
    (property "Author" "Antmicro" (id 6) (at 143.51 98.298 0)
      (effects (font (size 1.27 1.27) (thickness 0.15)) (justify left bottom) hide)
    )
    (property "License" "Apache-2.0" (id 7) (at 146.05 98.298 0)
      (effects (font (size 1.27 1.27) (thickness 0.15)) (justify left bottom) hide)
    )
    (pin "1")
  )

  (symbol (lib_id "sa800u-baseboard-hw:TP_0.75mm_SMD") (at 123.19 148.082 270) (unit 1)
    (in_bom yes) (on_board yes) (fields_autoplaced)
    (property "Reference" "TP79" (id 0) (at 125.73 151.2569 90)
      (effects (font (size 1.27 1.27)) (justify left))
    )
    (property "Value" "TP_0.75mm_SMD" (id 1) (at 123.19 148.082 0)
      (effects (font (size 1.27 1.27)) hide)
    )
    (property "Footprint" "sa800u-baseboard-hw-footprints:TP_SMD_0.75mm" (id 2) (at 123.19 148.082 0)
      (effects (font (size 1.27 1.27)) hide)
    )
    (property "Datasheet" "" (id 3) (at 123.19 148.082 0)
      (effects (font (size 1.27 1.27)) hide)
    )
    (property "MPN" "" (id 4) (at 107.95 165.862 0)
      (effects (font (size 1.27 1.27) (thickness 0.15)) (justify left bottom) hide)
    )
    (property "Manufacturer" "" (id 5) (at 105.41 165.862 0)
      (effects (font (size 1.27 1.27) (thickness 0.15)) (justify left bottom) hide)
    )
    (property "Author" "Antmicro" (id 6) (at 102.87 165.862 0)
      (effects (font (size 1.27 1.27) (thickness 0.15)) (justify left bottom) hide)
    )
    (property "License" "Apache-2.0" (id 7) (at 100.33 165.862 0)
      (effects (font (size 1.27 1.27) (thickness 0.15)) (justify left bottom) hide)
    )
    (pin "1")
  )

  (symbol (lib_id "sa800u-baseboard-hw:TP_0.75mm_SMD") (at 170.434 128.778 0) (unit 1)
    (in_bom yes) (on_board yes) (fields_autoplaced)
    (property "Reference" "TP80" (id 0) (at 175.006 128.7779 0)
      (effects (font (size 1.27 1.27)) (justify left))
    )
    (property "Value" "TP_0.75mm_SMD" (id 1) (at 170.434 128.778 0)
      (effects (font (size 1.27 1.27)) hide)
    )
    (property "Footprint" "sa800u-baseboard-hw-footprints:TP_SMD_0.75mm" (id 2) (at 170.434 128.778 0)
      (effects (font (size 1.27 1.27)) hide)
    )
    (property "Datasheet" "" (id 3) (at 170.434 128.778 0)
      (effects (font (size 1.27 1.27)) hide)
    )
    (property "MPN" "" (id 4) (at 188.214 144.018 0)
      (effects (font (size 1.27 1.27) (thickness 0.15)) (justify left bottom) hide)
    )
    (property "Manufacturer" "" (id 5) (at 188.214 146.558 0)
      (effects (font (size 1.27 1.27) (thickness 0.15)) (justify left bottom) hide)
    )
    (property "Author" "Antmicro" (id 6) (at 188.214 149.098 0)
      (effects (font (size 1.27 1.27) (thickness 0.15)) (justify left bottom) hide)
    )
    (property "License" "Apache-2.0" (id 7) (at 188.214 151.638 0)
      (effects (font (size 1.27 1.27) (thickness 0.15)) (justify left bottom) hide)
    )
    (pin "1")
  )

  (symbol (lib_id "sa800u-baseboard-hw:TP_0.75mm_SMD") (at 195.453 144.145 90) (unit 1)
    (in_bom yes) (on_board yes)
    (property "Reference" "TP81" (id 0) (at 193.04 138.811 90)
      (effects (font (size 1.27 1.27)) (justify right))
    )
    (property "Value" "TP_0.75mm_SMD" (id 1) (at 195.453 144.145 0)
      (effects (font (size 1.27 1.27)) hide)
    )
    (property "Footprint" "sa800u-baseboard-hw-footprints:TP_SMD_0.75mm" (id 2) (at 195.453 144.145 0)
      (effects (font (size 1.27 1.27)) hide)
    )
    (property "Datasheet" "" (id 3) (at 195.453 144.145 0)
      (effects (font (size 1.27 1.27)) hide)
    )
    (property "MPN" "" (id 4) (at 210.693 126.365 0)
      (effects (font (size 1.27 1.27) (thickness 0.15)) (justify left bottom) hide)
    )
    (property "Manufacturer" "" (id 5) (at 213.233 126.365 0)
      (effects (font (size 1.27 1.27) (thickness 0.15)) (justify left bottom) hide)
    )
    (property "Author" "Antmicro" (id 6) (at 215.773 126.365 0)
      (effects (font (size 1.27 1.27) (thickness 0.15)) (justify left bottom) hide)
    )
    (property "License" "Apache-2.0" (id 7) (at 218.313 126.365 0)
      (effects (font (size 1.27 1.27) (thickness 0.15)) (justify left bottom) hide)
    )
    (pin "1")
  )

  (symbol (lib_id "sa800u-baseboard-hw:GNDD") (at 195.453 145.288 0) (unit 1)
    (in_bom yes) (on_board yes) (fields_autoplaced)
    (property "Reference" "#PWR0246" (id 0) (at 195.453 151.638 0)
      (effects (font (size 1.27 1.27)) hide)
    )
    (property "Value" "GNDD" (id 1) (at 195.453 149.86 0))
    (property "Footprint" "" (id 2) (at 195.453 145.288 0)
      (effects (font (size 1.27 1.27)) hide)
    )
    (property "Datasheet" "" (id 3) (at 195.453 145.288 0)
      (effects (font (size 1.27 1.27)) hide)
    )
    (property "Author" "Antmicro" (id 4) (at 210.693 152.908 0)
      (effects (font (size 1.27 1.27) (thickness 0.15)) (justify left bottom) hide)
    )
    (property "License" "Apache-2.0" (id 5) (at 210.693 155.448 0)
      (effects (font (size 1.27 1.27) (thickness 0.15)) (justify left bottom) hide)
    )
    (pin "1")
  )

  (symbol (lib_id "sa800u-baseboard-hw:PWR_FLAG") (at 201.168 144.145 0) (unit 1)
    (in_bom yes) (on_board yes)
    (property "Reference" "#FLG0102" (id 0) (at 201.168 142.24 0)
      (effects (font (size 1.27 1.27)) hide)
    )
    (property "Value" "PWR_FLAG" (id 1) (at 201.295 140.589 0))
    (property "Footprint" "" (id 2) (at 201.168 144.145 0)
      (effects (font (size 1.27 1.27)) hide)
    )
    (property "Datasheet" "~" (id 3) (at 201.168 144.145 0)
      (effects (font (size 1.27 1.27)) hide)
    )
    (pin "1")
  )

  (symbol (lib_id "sa800u-baseboard-hw:PWR_FLAG") (at 111.252 146.05 0) (unit 1)
    (in_bom yes) (on_board yes)
    (property "Reference" "#FLG0103" (id 0) (at 111.252 144.145 0)
      (effects (font (size 1.27 1.27)) hide)
    )
    (property "Value" "PWR_FLAG" (id 1) (at 111.252 140.462 0))
    (property "Footprint" "" (id 2) (at 111.252 146.05 0)
      (effects (font (size 1.27 1.27)) hide)
    )
    (property "Datasheet" "~" (id 3) (at 111.252 146.05 0)
      (effects (font (size 1.27 1.27)) hide)
    )
    (pin "1")
  )

  (symbol (lib_id "sa800u-baseboard-hw:GNDD") (at 201.168 145.288 0) (unit 1)
    (in_bom yes) (on_board yes) (fields_autoplaced)
    (property "Reference" "#PWR0106" (id 0) (at 201.168 151.638 0)
      (effects (font (size 1.27 1.27)) hide)
    )
    (property "Value" "GNDD" (id 1) (at 201.168 149.86 0))
    (property "Footprint" "" (id 2) (at 201.168 145.288 0)
      (effects (font (size 1.27 1.27)) hide)
    )
    (property "Datasheet" "" (id 3) (at 201.168 145.288 0)
      (effects (font (size 1.27 1.27)) hide)
    )
    (property "Author" "Antmicro" (id 4) (at 216.408 152.908 0)
      (effects (font (size 1.27 1.27) (thickness 0.15)) (justify left bottom) hide)
    )
    (property "License" "Apache-2.0" (id 5) (at 216.408 155.448 0)
      (effects (font (size 1.27 1.27) (thickness 0.15)) (justify left bottom) hide)
    )
    (pin "1")
  )

  (symbol (lib_id "sa800u-baseboard-hw:PWR_FLAG") (at 117.856 114.808 0) (unit 1)
    (in_bom yes) (on_board yes)
    (property "Reference" "#FLG0101" (id 0) (at 117.856 112.903 0)
      (effects (font (size 1.27 1.27)) hide)
    )
    (property "Value" "PWR_FLAG" (id 1) (at 117.856 109.22 0))
    (property "Footprint" "" (id 2) (at 117.856 114.808 0)
      (effects (font (size 1.27 1.27)) hide)
    )
    (property "Datasheet" "~" (id 3) (at 117.856 114.808 0)
      (effects (font (size 1.27 1.27)) hide)
    )
    (pin "1")
  )
)
